(kicad_pcb
	(version 20260206)
	(generator "pcbnew")
	(generator_version "10.0")
	(general
		(thickness 1.6)
		(legacy_teardrops no)
	)
	(paper "A4")
	(title_block
		(title "baseboard — 13948-1b.1110WZS1818.brd")
		(comment 1 "Honey Badger (Wiwynn) / footprints 1149-1154 of 2523")
	)
	(layers
		(0 "F.Cu" signal "TOP")
		(4 "In1.Cu" signal "L2GND")
		(6 "In2.Cu" signal "L3")
		(8 "In3.Cu" signal "L4VCC")
		(10 "In4.Cu" signal "L5VCC")
		(12 "In5.Cu" signal "L6")
		(14 "In6.Cu" signal "L7GND")
		(2 "B.Cu" signal "BOTTOM")
		(9 "F.Adhes" user "F.Adhesive")
		(11 "B.Adhes" user "B.Adhesive")
		(13 "F.Paste" user "Package Geometry/Pastemask Top")
		(15 "B.Paste" user "Package Geometry/Pastemask Bottom")
		(5 "F.SilkS" user "Ref Des/Silkscreen Top")
		(7 "B.SilkS" user "Ref Des/Silkscreen Bottom")
		(1 "F.Mask" user "Board Geometry/Soldermask Top")
		(3 "B.Mask" user "Board Geometry/Soldermask Bottom")
		(17 "Dwgs.User" user "User.Drawings")
		(19 "Cmts.User" user "User.Comments")
		(21 "Eco1.User" user "User.Eco1")
		(23 "Eco2.User" user "User.Eco2")
		(25 "Edge.Cuts" user "Board Geometry/Outline")
		(27 "Margin" user)
		(31 "F.CrtYd" user "Package Geometry/Place Bound Top")
		(29 "B.CrtYd" user "Package Geometry/Place Bound Bottom")
		(35 "F.Fab" user "Ref Des/Assembly Top")
		(33 "B.Fab" user "Ref Des/Assembly Bottom")
	)
	(footprint ""
		(layer "F.Cu")
		(at 289.941 -218.948 -90)
		(property "Reference" "PC81"
			(at 0 0 270)
			(layer "F.SilkS")
			(hide yes)
			(effects
				(font
					(size 1.27 1.27)
				)
			)
		)
		(property "Value" "SC1KP50V2KX-1GP"
			(at 1.1811 -2.7051 270)
			(unlocked yes)
			(layer "F.Fab")
			(hide yes)
			(effects
				(font
					(size 1.016 1.016)
					(thickness 0.1524)
				)
			)
		)
		(property "Device Type" "C402H22"
			(at 1.1811 -4.2291 270)
			(unlocked yes)
			(layer "F.Fab")
			(hide yes)
			(effects
				(font
					(size 1.016 1.016)
					(thickness 0.1524)
				)
			)
		)
		(duplicate_pad_numbers_are_jumpers no)
		(fp_rect
			(start -0.4318 0.9525)
			(end 0.4318 -0.9525)
			(stroke
				(width 0)
				(type default)
			)
			(fill no)
			(layer "F.CrtYd")
		)
		(fp_rect
			(start -0.4318 0.9525)
			(end 0.4318 -0.9525)
			(stroke
				(width 0)
				(type default)
			)
			(fill no)
			(layer "F.Fab")
		)
		(pad "1" smd custom
			(at 0 -0.4445 270)
			(size 0.1524 0.1524)
			(layers "F.Cu" "F.Mask" "F.Paste")
			(net "TPS74801_1V53_STBY_OUT")
			(options
				(clearance outline)
				(anchor circle)
			)
			(primitives
				(gr_poly
					(pts
						(arc
							(start 0.3048 -0.2032)
							(mid 0.275042 -0.275042)
							(end 0.2032 -0.3048)
						)
						(arc
							(start -0.2032 -0.3048)
							(mid -0.275042 -0.275042)
							(end -0.3048 -0.2032)
						)
						(arc
							(start -0.3048 0.2032)
							(mid -0.275042 0.275042)
							(end -0.2032 0.3048)
						)
						(arc
							(start 0.2032 0.3048)
							(mid 0.275042 0.275042)
							(end 0.3048 0.2032)
						)
					)
					(width 0)
					(fill yes)
				)
			)
		)
		(pad "2" smd custom
			(at 0 0.4445 270)
			(size 0.1524 0.1524)
			(layers "F.Cu" "F.Mask" "F.Paste")
			(net "TPS74801_1V53_STBY_FB")
			(options
				(clearance outline)
				(anchor circle)
			)
			(primitives
				(gr_poly
					(pts
						(arc
							(start 0.3048 -0.2032)
							(mid 0.275042 -0.275042)
							(end 0.2032 -0.3048)
						)
						(arc
							(start -0.2032 -0.3048)
							(mid -0.275042 -0.275042)
							(end -0.3048 -0.2032)
						)
						(arc
							(start -0.3048 0.2032)
							(mid -0.275042 0.275042)
							(end -0.2032 0.3048)
						)
						(arc
							(start 0.2032 0.3048)
							(mid 0.275042 0.275042)
							(end 0.3048 0.2032)
						)
					)
					(width 0)
					(fill yes)
				)
			)
		)
	)
	(footprint ""
		(layer "F.Cu")
		(at 78.73619 -55.339488 -90)
		(property "Reference" "SC930"
			(at 0 0 270)
			(layer "F.SilkS")
			(hide yes)
			(effects
				(font
					(size 1.27 1.27)
				)
			)
		)
		(property "Value" "SCD1U6D3V1KX-GP"
			(at -2.8321 -1.7399 270)
			(unlocked yes)
			(layer "F.Fab")
			(hide yes)
			(effects
				(font
					(size 1.016 1.016)
					(thickness 0.1524)
				)
			)
		)
		(property "Device Type" "C0201H13"
			(at -2.8321 -3.2639 270)
			(unlocked yes)
			(layer "F.Fab")
			(hide yes)
			(effects
				(font
					(size 1.016 1.016)
					(thickness 0.1524)
				)
			)
		)
		(duplicate_pad_numbers_are_jumpers no)
		(fp_rect
			(start -0.2794 0.6477)
			(end 0.2794 -0.6477)
			(stroke
				(width 0)
				(type default)
			)
			(fill no)
			(layer "F.CrtYd")
		)
		(fp_rect
			(start -0.2794 0.6477)
			(end 0.2794 -0.6477)
			(stroke
				(width 0)
				(type default)
			)
			(fill no)
			(layer "F.Fab")
		)
		(pad "1" smd custom
			(at 0 -0.2794 270)
			(size 0.0762 0.0762)
			(layers "F.Cu" "F.Mask" "F.Paste")
			(net "SHELL_PLL_VDD")
			(options
				(clearance outline)
				(anchor circle)
			)
			(primitives
				(gr_poly
					(pts
						(arc
							(start 0.1524 -0.127)
							(mid 0.137521 -0.162921)
							(end 0.1016 -0.1778)
						)
						(arc
							(start -0.1016 -0.1778)
							(mid -0.137521 -0.162921)
							(end -0.1524 -0.127)
						)
						(arc
							(start -0.1524 0.127)
							(mid -0.137521 0.162921)
							(end -0.1016 0.1778)
						)
						(arc
							(start 0.1016 0.1778)
							(mid 0.137521 0.162921)
							(end 0.1524 0.127)
						)
					)
					(width 0)
					(fill yes)
				)
			)
		)
		(pad "2" smd custom
			(at 0 0.2794 270)
			(size 0.0762 0.0762)
			(layers "F.Cu" "F.Mask" "F.Paste")
			(net "GND")
			(options
				(clearance outline)
				(anchor circle)
			)
			(primitives
				(gr_poly
					(pts
						(arc
							(start 0.1524 -0.127)
							(mid 0.137521 -0.162921)
							(end 0.1016 -0.1778)
						)
						(arc
							(start -0.1016 -0.1778)
							(mid -0.137521 -0.162921)
							(end -0.1524 -0.127)
						)
						(arc
							(start -0.1524 0.127)
							(mid -0.137521 0.162921)
							(end -0.1016 0.1778)
						)
						(arc
							(start 0.1016 0.1778)
							(mid 0.137521 0.162921)
							(end 0.1524 0.127)
						)
					)
					(width 0)
					(fill yes)
				)
			)
		)
	)
	(footprint ""
		(layer "F.Cu")
		(at 80.264 -28.194 90)
		(property "Reference" "SL9"
			(at 0 0 90)
			(layer "F.SilkS")
			(hide yes)
			(effects
				(font
					(size 1.27 1.27)
				)
			)
		)
		(property "Value" "28F0181-1SR-10-GP"
			(at -4.064 -3.5052 90)
			(unlocked yes)
			(layer "F.Fab")
			(hide yes)
			(effects
				(font
					(size 1.016 1.016)
					(thickness 0.1524)
				)
			)
		)
		(property "Device Type" "L9546-152127H121"
			(at -4.064 -5.0292 90)
			(unlocked yes)
			(layer "F.Fab")
			(hide yes)
			(effects
				(font
					(size 1.016 1.016)
					(thickness 0.1524)
				)
			)
		)
		(duplicate_pad_numbers_are_jumpers no)
		(fp_line
			(start 2.54 -5.6642)
			(end -2.54 -5.6642)
			(stroke
				(width 0.1524)
				(type default)
			)
			(layer "F.SilkS")
		)
		(fp_line
			(start -2.54 -5.6642)
			(end -2.54 5.6642)
			(stroke
				(width 0.1524)
				(type default)
			)
			(layer "F.SilkS")
		)
		(fp_line
			(start 2.54 5.6642)
			(end 2.54 -5.6642)
			(stroke
				(width 0.1524)
				(type default)
			)
			(layer "F.SilkS")
		)
		(fp_line
			(start -2.54 5.6642)
			(end 2.54 5.6642)
			(stroke
				(width 0.1524)
				(type default)
			)
			(layer "F.SilkS")
		)
		(fp_rect
			(start -2.286 4.7625)
			(end 2.286 -4.7625)
			(stroke
				(width 0)
				(type default)
			)
			(fill no)
			(layer "F.CrtYd")
		)
		(fp_poly
			(pts
				(xy -2.794 5.7404) (xy -2.794 -5.7404) (xy 2.794 -5.7404) (xy 2.794 5.7404) (xy 0.00254 5.7404)
				(xy 0.00254 4.7625) (xy 2.286 4.7625) (xy 2.286 -4.7625) (xy -2.286 -4.7625) (xy -2.286 4.7625)
				(xy -0.00254 4.7625) (xy -0.00254 5.7404)
			)
			(stroke
				(width 0)
				(type default)
			)
			(fill no)
			(layer "F.CrtYd")
		)
		(fp_rect
			(start -2.794 5.7404)
			(end 2.794 -5.7404)
			(stroke
				(width 0)
				(type default)
			)
			(fill no)
			(layer "F.Fab")
		)
		(pad "1" smd rect
			(at 0 -4.197604 90)
			(size 1.524 2.413)
			(layers "F.Cu" "F.Mask" "F.Paste")
			(net "P0V955_C")
		)
		(pad "2" smd rect
			(at 0 4.197604 90)
			(size 1.524 2.413)
			(layers "F.Cu" "F.Mask" "F.Paste")
			(net "SAS0_AVDD")
		)
	)
	(footprint ""
		(layer "F.Cu")
		(at 334.509872 -232.482136)
		(property "Reference" "R186"
			(at 0 0 0)
			(layer "F.SilkS")
			(hide yes)
			(effects
				(font
					(size 1.27 1.27)
				)
			)
		)
		(property "Value" "4K7R2F-GP"
			(at 0.064008 -3.993896 0)
			(unlocked yes)
			(layer "F.Fab")
			(hide yes)
			(effects
				(font
					(size 1.016 1.016)
					(thickness 0.1524)
				)
			)
		)
		(property "Device Type" "R402H16"
			(at 0.064008 -5.517896 0)
			(unlocked yes)
			(layer "F.Fab")
			(hide yes)
			(effects
				(font
					(size 1.016 1.016)
					(thickness 0.1524)
				)
			)
		)
		(duplicate_pad_numbers_are_jumpers no)
		(fp_line
			(start -0.508 -0.9398)
			(end -0.508 0.9398)
			(stroke
				(width 0.1524)
				(type default)
			)
			(layer "F.SilkS")
		)
		(fp_line
			(start 0.508 -0.9398)
			(end -0.508 -0.9398)
			(stroke
				(width 0.1524)
				(type default)
			)
			(layer "F.SilkS")
		)
		(fp_rect
			(start -0.508 0.9398)
			(end 0.508 -0.9398)
			(stroke
				(width 0)
				(type default)
			)
			(fill no)
			(layer "F.CrtYd")
		)
		(fp_rect
			(start -0.508 0.9398)
			(end 0.508 -0.9398)
			(stroke
				(width 0)
				(type default)
			)
			(fill no)
			(layer "F.Fab")
		)
		(pad "1" smd custom
			(at 0 -0.4445)
			(size 0.1397 0.1397)
			(layers "F.Cu" "F.Mask" "F.Paste")
			(net "P3V3_STBY")
			(options
				(clearance outline)
				(anchor circle)
			)
			(primitives
				(gr_poly
					(pts
						(arc
							(start -0.1778 -0.2794)
							(mid -0.249642 -0.249642)
							(end -0.2794 -0.1778)
						)
						(arc
							(start -0.2794 0.1778)
							(mid -0.249642 0.249642)
							(end -0.1778 0.2794)
						)
						(arc
							(start 0.1778 0.2794)
							(mid 0.249642 0.249642)
							(end 0.2794 0.1778)
						)
						(arc
							(start 0.2794 -0.1778)
							(mid 0.249642 -0.249642)
							(end 0.1778 -0.2794)
						)
					)
					(width 0)
					(fill yes)
				)
			)
		)
		(pad "2" smd custom
			(at 0 0.4445)
			(size 0.1397 0.1397)
			(layers "F.Cu" "F.Mask" "F.Paste")
			(net "VOL_SEN_ADDR")
			(options
				(clearance outline)
				(anchor circle)
			)
			(primitives
				(gr_poly
					(pts
						(arc
							(start -0.1778 -0.2794)
							(mid -0.249642 -0.249642)
							(end -0.2794 -0.1778)
						)
						(arc
							(start -0.2794 0.1778)
							(mid -0.249642 0.249642)
							(end -0.1778 0.2794)
						)
						(arc
							(start 0.1778 0.2794)
							(mid 0.249642 0.249642)
							(end 0.2794 0.1778)
						)
						(arc
							(start 0.2794 -0.1778)
							(mid 0.249642 -0.249642)
							(end 0.1778 -0.2794)
						)
					)
					(width 0)
					(fill yes)
				)
			)
		)
	)
	(footprint ""
		(layer "F.Cu")
		(at 310.896 -182.499 -90)
		(property "Reference" "R308"
			(at 0 0 270)
			(layer "F.SilkS")
			(hide yes)
			(effects
				(font
					(size 1.27 1.27)
				)
			)
		)
		(property "Value" "0R2J-2-GP"
			(at 0.064008 -3.993896 270)
			(unlocked yes)
			(layer "F.Fab")
			(hide yes)
			(effects
				(font
					(size 1.016 1.016)
					(thickness 0.1524)
				)
			)
		)
		(property "Device Type" "R402H16"
			(at 0.064008 -5.517896 270)
			(unlocked yes)
			(layer "F.Fab")
			(hide yes)
			(effects
				(font
					(size 1.016 1.016)
					(thickness 0.1524)
				)
			)
		)
		(duplicate_pad_numbers_are_jumpers no)
		(fp_line
			(start -0.508 -0.9398)
			(end -0.508 0.9398)
			(stroke
				(width 0.1524)
				(type default)
			)
			(layer "F.SilkS")
		)
		(fp_line
			(start 0.508 -0.9398)
			(end -0.508 -0.9398)
			(stroke
				(width 0.1524)
				(type default)
			)
			(layer "F.SilkS")
		)
		(fp_rect
			(start -0.508 0.9398)
			(end 0.508 -0.9398)
			(stroke
				(width 0)
				(type default)
			)
			(fill no)
			(layer "F.CrtYd")
		)
		(fp_rect
			(start -0.508 0.9398)
			(end 0.508 -0.9398)
			(stroke
				(width 0)
				(type default)
			)
			(fill no)
			(layer "F.Fab")
		)
		(pad "1" smd custom
			(at 0 -0.4445 270)
			(size 0.1397 0.1397)
			(layers "F.Cu" "F.Mask" "F.Paste")
			(net "FAN_PWM_PCIE")
			(options
				(clearance outline)
				(anchor circle)
			)
			(primitives
				(gr_poly
					(pts
						(arc
							(start -0.1778 -0.2794)
							(mid -0.249642 -0.249642)
							(end -0.2794 -0.1778)
						)
						(arc
							(start -0.2794 0.1778)
							(mid -0.249642 0.249642)
							(end -0.1778 0.2794)
						)
						(arc
							(start 0.1778 0.2794)
							(mid 0.249642 0.249642)
							(end 0.2794 0.1778)
						)
						(arc
							(start 0.2794 -0.1778)
							(mid 0.249642 -0.249642)
							(end 0.1778 -0.2794)
						)
					)
					(width 0)
					(fill yes)
				)
			)
		)
		(pad "2" smd custom
			(at 0 0.4445 270)
			(size 0.1397 0.1397)
			(layers "F.Cu" "F.Mask" "F.Paste")
			(net "FAN_PWM_PCIE_BMC")
			(options
				(clearance outline)
				(anchor circle)
			)
			(primitives
				(gr_poly
					(pts
						(arc
							(start -0.1778 -0.2794)
							(mid -0.249642 -0.249642)
							(end -0.2794 -0.1778)
						)
						(arc
							(start -0.2794 0.1778)
							(mid -0.249642 0.249642)
							(end -0.1778 0.2794)
						)
						(arc
							(start 0.1778 0.2794)
							(mid 0.249642 0.249642)
							(end 0.2794 0.1778)
						)
						(arc
							(start 0.2794 -0.1778)
							(mid 0.249642 -0.249642)
							(end 0.1778 -0.2794)
						)
					)
					(width 0)
					(fill yes)
				)
			)
		)
	)
	(footprint ""
		(layer "F.Cu")
		(at 296.545 -158.115 180)
		(property "Reference" "R291"
			(at 0 0 180)
			(layer "F.SilkS")
			(hide yes)
			(effects
				(font
					(size 1.27 1.27)
				)
			)
		)
		(property "Value" "0R2J-2-GP"
			(at 0.064008 -3.993896 180)
			(unlocked yes)
			(layer "F.Fab")
			(hide yes)
			(effects
				(font
					(size 1.016 1.016)
					(thickness 0.1524)
				)
			)
		)
		(property "Device Type" "R402H16"
			(at 0.064008 -5.517896 180)
			(unlocked yes)
			(layer "F.Fab")
			(hide yes)
			(effects
				(font
					(size 1.016 1.016)
					(thickness 0.1524)
				)
			)
		)
		(duplicate_pad_numbers_are_jumpers no)
		(fp_line
			(start 0.508 -0.9398)
			(end -0.508 -0.9398)
			(stroke
				(width 0.1524)
				(type default)
			)
			(layer "F.SilkS")
		)
		(fp_line
			(start -0.508 -0.9398)
			(end -0.508 0.9398)
			(stroke
				(width 0.1524)
				(type default)
			)
			(layer "F.SilkS")
		)
		(fp_rect
			(start -0.508 0.9398)
			(end 0.508 -0.9398)
			(stroke
				(width 0)
				(type default)
			)
			(fill no)
			(layer "F.CrtYd")
		)
		(fp_rect
			(start -0.508 0.9398)
			(end 0.508 -0.9398)
			(stroke
				(width 0)
				(type default)
			)
			(fill no)
			(layer "F.Fab")
		)
		(pad "1" smd custom
			(at 0 -0.4445 180)
			(size 0.1397 0.1397)
			(layers "F.Cu" "F.Mask" "F.Paste")
			(net "GND")
			(options
				(clearance outline)
				(anchor circle)
			)
			(primitives
				(gr_poly
					(pts
						(arc
							(start -0.1778 -0.2794)
							(mid -0.249642 -0.249642)
							(end -0.2794 -0.1778)
						)
						(arc
							(start -0.2794 0.1778)
							(mid -0.249642 0.249642)
							(end -0.1778 0.2794)
						)
						(arc
							(start 0.1778 0.2794)
							(mid 0.249642 0.249642)
							(end 0.2794 0.1778)
						)
						(arc
							(start 0.2794 -0.1778)
							(mid 0.249642 -0.249642)
							(end 0.1778 -0.2794)
						)
					)
					(width 0)
					(fill yes)
				)
			)
		)
		(pad "2" smd custom
			(at 0 0.4445 180)
			(size 0.1397 0.1397)
			(layers "F.Cu" "F.Mask" "F.Paste")
			(net "CLK_50M_BMC0")
			(options
				(clearance outline)
				(anchor circle)
			)
			(primitives
				(gr_poly
					(pts
						(arc
							(start -0.1778 -0.2794)
							(mid -0.249642 -0.249642)
							(end -0.2794 -0.1778)
						)
						(arc
							(start -0.2794 0.1778)
							(mid -0.249642 0.249642)
							(end -0.1778 0.2794)
						)
						(arc
							(start 0.1778 0.2794)
							(mid 0.249642 0.249642)
							(end 0.2794 0.1778)
						)
						(arc
							(start 0.2794 -0.1778)
							(mid 0.249642 -0.249642)
							(end 0.1778 -0.2794)
						)
					)
					(width 0)
					(fill yes)
				)
			)
		)
	)
)
